(kicad_pcb
	(version 20241229)
	(generator "pcbnew")
	(generator_version "9.0")
	(general
		(thickness 1.292)
		(legacy_teardrops no)
	)
	(paper "A4")
	(title_block
		(title "LPDDR5 Testbed")
		(date "2023-12-19")
		(rev "1.0.0")
		(comment 9 "footprint 12 of 160 (U1), pads 90-182 of 315")
	)
	(layers
		(0 "F.Cu" signal)
		(4 "In1.Cu" power)
		(6 "In2.Cu" power)
		(8 "In3.Cu" signal)
		(10 "In4.Cu" signal)
		(2 "B.Cu" signal)
		(9 "F.Adhes" user "F.Adhesive")
		(11 "B.Adhes" user "B.Adhesive")
		(13 "F.Paste" user)
		(15 "B.Paste" user)
		(5 "F.SilkS" user "F.Silkscreen")
		(7 "B.SilkS" user "B.Silkscreen")
		(1 "F.Mask" user)
		(3 "B.Mask" user)
		(17 "Dwgs.User" user "User.Drawings")
		(19 "Cmts.User" user "User.Comments")
		(21 "Eco1.User" user "User.Eco1")
		(23 "Eco2.User" user "User.Eco2")
		(25 "Edge.Cuts" user)
		(27 "Margin" user)
		(31 "F.CrtYd" user "F.Courtyard")
		(29 "B.CrtYd" user "B.Courtyard")
		(35 "F.Fab" user)
		(33 "B.Fab" user)
	)
	(footprint "antmicro-footprints:BGA-315_12.4x15mm_Layout15x21_P0.8x0.7mm"
		(layer "F.Cu")
		(at 134.775 80 90)
		(property "Reference" "U1"
			(at 6.8 7.025 0)
			(unlocked yes)
			(layer "F.SilkS")
			(effects
				(font
					(size 0.7 0.7)
					(thickness 0.15)
				)
				(justify left bottom)
			)
		)
		(property "Value" "MT62F1G32D4DR-031"
			(at 0 8.9 90)
			(layer "F.Fab")
			(effects
				(font
					(size 0.7 0.7)
					(thickness 0.15)
				)
				(justify left bottom)
			)
		)
		(property "Author" "Antmicro"
			(at 214.775 -54.775 0)
			(layer "F.Fab")
			(hide yes)
			(effects
				(font
					(size 1 1)
					(thickness 0.15)
				)
			)
		)
		(property "License" "Apache-2.0"
			(at 214.775 -54.775 0)
			(layer "F.Fab")
			(hide yes)
			(effects
				(font
					(size 1 1)
					(thickness 0.15)
				)
			)
		)
		(property "MPN" "MT62F1G32D4DR-031 WT:B"
			(at 214.775 -54.775 0)
			(layer "F.Fab")
			(hide yes)
			(effects
				(font
					(size 1 1)
					(thickness 0.15)
				)
			)
		)
		(property "Manufacturer" "Micron Technology"
			(at 214.775 -54.775 0)
			(layer "F.Fab")
			(hide yes)
			(effects
				(font
					(size 1 1)
					(thickness 0.15)
				)
			)
		)
		(sheetname "LPDDR5")
		(sheetfile "lpddr5.kicad_sch")
		(attr smd)
		(pad "E15" smd circle
			(at 5.6 -4.2 90)
			(size 0.41 0.41)
			(layers "F.Cu" "F.Mask" "F.Paste")
			(net 14 "GND")
			(pinfunction "VSS")
			(pintype "passive")
		)
		(pad "F1" smd circle
			(at -5.6 -3.5 90)
			(size 0.41 0.41)
			(layers "F.Cu" "F.Mask" "F.Paste")
			(net 4 "+0V5")
			(pinfunction "VDDQ")
			(pintype "passive")
		)
		(pad "F2" smd circle
			(at -4.8 -3.5 90)
			(size 0.41 0.41)
			(layers "F.Cu" "F.Mask" "F.Paste")
			(net 14 "GND")
			(pinfunction "VSS")
			(pintype "passive")
		)
		(pad "F3" smd circle
			(at -4 -3.5 90)
			(size 0.41 0.41)
			(layers "F.Cu" "F.Mask" "F.Paste")
			(net 4 "+0V5")
			(pinfunction "VDDQ")
			(pintype "passive")
		)
		(pad "F4" smd circle
			(at -3.2 -3.5 90)
			(size 0.41 0.41)
			(layers "F.Cu" "F.Mask" "F.Paste")
			(net 4 "+0V5")
			(pinfunction "VDDQ")
			(pintype "passive")
		)
		(pad "F5" smd circle
			(at -2.4 -3.5 90)
			(size 0.41 0.41)
			(layers "F.Cu" "F.Mask" "F.Paste")
			(net 195 "/LPDDR5/LPDDR5_A.DQ7")
			(pinfunction "DQ7_A")
			(pintype "passive")
		)
		(pad "F6" smd circle
			(at -1.6 -3.5 90)
			(size 0.41 0.41)
			(layers "F.Cu" "F.Mask" "F.Paste")
			(net 13 "+1V05")
			(pinfunction "VDD2H")
			(pintype "passive")
		)
		(pad "F7" smd circle
			(at -0.8 -3.5 90)
			(size 0.41 0.41)
			(layers "F.Cu" "F.Mask" "F.Paste")
			(net 13 "+1V05")
			(pinfunction "VDD2H")
			(pintype "passive")
		)
		(pad "F8" smd circle
			(at 0 -3.5 90)
			(size 0.41 0.41)
			(layers "F.Cu" "F.Mask" "F.Paste")
			(net 14 "GND")
			(pinfunction "VSS")
			(pintype "passive")
		)
		(pad "F9" smd circle
			(at 0.8 -3.5 90)
			(size 0.41 0.41)
			(layers "F.Cu" "F.Mask" "F.Paste")
			(net 13 "+1V05")
			(pinfunction "VDD2H")
			(pintype "passive")
		)
		(pad "F10" smd circle
			(at 1.6 -3.5 90)
			(size 0.41 0.41)
			(layers "F.Cu" "F.Mask" "F.Paste")
			(net 13 "+1V05")
			(pinfunction "VDD2H")
			(pintype "passive")
		)
		(pad "F11" smd circle
			(at 2.4 -3.5 90)
			(size 0.41 0.41)
			(layers "F.Cu" "F.Mask" "F.Paste")
			(net 191 "/LPDDR5/LPDDR5_A.DQ15")
			(pinfunction "DQ15_A")
			(pintype "passive")
		)
		(pad "F12" smd circle
			(at 3.2 -3.5 90)
			(size 0.41 0.41)
			(layers "F.Cu" "F.Mask" "F.Paste")
			(net 4 "+0V5")
			(pinfunction "VDDQ")
			(pintype "passive")
		)
		(pad "F13" smd circle
			(at 4 -3.5 90)
			(size 0.41 0.41)
			(layers "F.Cu" "F.Mask" "F.Paste")
			(net 4 "+0V5")
			(pinfunction "VDDQ")
			(pintype "passive")
		)
		(pad "F14" smd circle
			(at 4.8 -3.5 90)
			(size 0.41 0.41)
			(layers "F.Cu" "F.Mask" "F.Paste")
			(net 14 "GND")
			(pinfunction "VSS")
			(pintype "passive")
		)
		(pad "F15" smd circle
			(at 5.6 -3.5 90)
			(size 0.41 0.41)
			(layers "F.Cu" "F.Mask" "F.Paste")
			(net 4 "+0V5")
			(pinfunction "VDDQ")
			(pintype "passive")
		)
		(pad "G1" smd circle
			(at -5.6 -2.8 90)
			(size 0.41 0.41)
			(layers "F.Cu" "F.Mask" "F.Paste")
			(net 4 "+0V5")
			(pinfunction "VDDQ")
			(pintype "passive")
		)
		(pad "G2" smd circle
			(at -4.8 -2.8 90)
			(size 0.41 0.41)
			(layers "F.Cu" "F.Mask" "F.Paste")
			(net 4 "+0V5")
			(pinfunction "VDDQ")
			(pintype "passive")
		)
		(pad "G3" smd circle
			(at -4 -2.8 90)
			(size 0.41 0.41)
			(layers "F.Cu" "F.Mask" "F.Paste")
			(net 14 "GND")
			(pinfunction "VSS")
			(pintype "passive")
		)
		(pad "G4" smd circle
			(at -3.2 -2.8 90)
			(size 0.41 0.41)
			(layers "F.Cu" "F.Mask" "F.Paste")
			(net 57 "/LPDDR5/LPDDR5_A.CA0")
			(pinfunction "CA0_A")
			(pintype "passive")
		)
		(pad "G5" smd circle
			(at -2.4 -2.8 90)
			(size 0.41 0.41)
			(layers "F.Cu" "F.Mask" "F.Paste")
			(net 14 "GND")
			(pinfunction "VSS")
			(pintype "passive")
		)
		(pad "G6" smd circle
			(at -1.6 -2.8 90)
			(size 0.41 0.41)
			(layers "F.Cu" "F.Mask" "F.Paste")
			(net 44 "/LPDDR5/LPDDR5_A.CS1")
			(pinfunction "CS1_A")
			(pintype "passive")
		)
		(pad "G7" smd circle
			(at -0.8 -2.8 90)
			(size 0.41 0.41)
			(layers "F.Cu" "F.Mask" "F.Paste")
			(net 14 "GND")
			(pinfunction "VSS")
			(pintype "passive")
		)
		(pad "G8" smd circle
			(at 0 -2.8 90)
			(size 0.41 0.41)
			(layers "F.Cu" "F.Mask" "F.Paste")
			(net 59 "/LPDDR5/LPDDR5_A.CA2")
			(pinfunction "CA2_A")
			(pintype "passive")
		)
		(pad "G9" smd circle
			(at 0.8 -2.8 90)
			(size 0.41 0.41)
			(layers "F.Cu" "F.Mask" "F.Paste")
			(net 14 "GND")
			(pinfunction "VSS")
			(pintype "passive")
		)
		(pad "G10" smd circle
			(at 1.6 -2.8 90)
			(size 0.41 0.41)
			(layers "F.Cu" "F.Mask" "F.Paste")
			(net 60 "/LPDDR5/LPDDR5_A.CA4")
			(pinfunction "CA4_A")
			(pintype "passive")
		)
		(pad "G11" smd circle
			(at 2.4 -2.8 90)
			(size 0.41 0.41)
			(layers "F.Cu" "F.Mask" "F.Paste")
			(net 14 "GND")
			(pinfunction "VSS")
			(pintype "passive")
		)
		(pad "G12" smd circle
			(at 3.2 -2.8 90)
			(size 0.41 0.41)
			(layers "F.Cu" "F.Mask" "F.Paste")
			(net 55 "/LPDDR5/LPDDR5_A.CA6")
			(pinfunction "CA6_A")
			(pintype "passive")
		)
		(pad "G13" smd circle
			(at 4 -2.8 90)
			(size 0.41 0.41)
			(layers "F.Cu" "F.Mask" "F.Paste")
			(net 14 "GND")
			(pinfunction "VSS")
			(pintype "passive")
		)
		(pad "G14" smd circle
			(at 4.8 -2.8 90)
			(size 0.41 0.41)
			(layers "F.Cu" "F.Mask" "F.Paste")
			(net 4 "+0V5")
			(pinfunction "VDDQ")
			(pintype "passive")
		)
		(pad "G15" smd circle
			(at 5.6 -2.8 90)
			(size 0.41 0.41)
			(layers "F.Cu" "F.Mask" "F.Paste")
			(net 4 "+0V5")
			(pinfunction "VDDQ")
			(pintype "passive")
		)
		(pad "H1" smd circle
			(at -5.6 -2.1 90)
			(size 0.41 0.41)
			(layers "F.Cu" "F.Mask" "F.Paste")
			(net 40 "/LPDDR5/~{RESET}")
			(pinfunction "RESET_n")
			(pintype "passive")
		)
		(pad "H2" smd circle
			(at -4.8 -2.1 90)
			(size 0.41 0.41)
			(layers "F.Cu" "F.Mask" "F.Paste")
			(net 12 "+0V9")
			(pinfunction "VDD2L")
			(pintype "passive")
		)
		(pad "H3" smd circle
			(at -4 -2.1 90)
			(size 0.41 0.41)
			(layers "F.Cu" "F.Mask" "F.Paste")
			(net 14 "GND")
			(pinfunction "VSS")
			(pintype "passive")
		)
		(pad "H4" smd circle
			(at -3.2 -2.1 90)
			(size 0.41 0.41)
			(layers "F.Cu" "F.Mask" "F.Paste")
			(net 14 "GND")
			(pinfunction "VSS")
			(pintype "passive")
		)
		(pad "H5" smd circle
			(at -2.4 -2.1 90)
			(size 0.41 0.41)
			(layers "F.Cu" "F.Mask" "F.Paste")
			(net 58 "/LPDDR5/LPDDR5_A.CA1")
			(pinfunction "CA1_A")
			(pintype "passive")
		)
		(pad "H6" smd circle
			(at -1.6 -2.1 90)
			(size 0.41 0.41)
			(layers "F.Cu" "F.Mask" "F.Paste")
			(net 14 "GND")
			(pinfunction "VSS")
			(pintype "passive")
		)
		(pad "H7" smd circle
			(at -0.8 -2.1 90)
			(size 0.41 0.41)
			(layers "F.Cu" "F.Mask" "F.Paste")
			(net 43 "/LPDDR5/LPDDR5_A.CS0")
			(pinfunction "CS0_A")
			(pintype "passive")
		)
		(pad "H8" smd circle
			(at 0 -2.1 90)
			(size 0.41 0.41)
			(layers "F.Cu" "F.Mask" "F.Paste")
			(net 14 "GND")
			(pinfunction "VSS")
			(pintype "passive")
		)
		(pad "H9" smd circle
			(at 0.8 -2.1 90)
			(size 0.41 0.41)
			(layers "F.Cu" "F.Mask" "F.Paste")
			(net 49 "/LPDDR5/LPDDR5_A.CK_P")
			(pinfunction "CK_t_A")
			(pintype "passive")
		)
		(pad "H10" smd circle
			(at 1.6 -2.1 90)
			(size 0.41 0.41)
			(layers "F.Cu" "F.Mask" "F.Paste")
			(net 14 "GND")
			(pinfunction "VSS")
			(pintype "passive")
		)
		(pad "H11" smd circle
			(at 2.4 -2.1 90)
			(size 0.41 0.41)
			(layers "F.Cu" "F.Mask" "F.Paste")
			(net 54 "/LPDDR5/LPDDR5_A.CA3")
			(pinfunction "CA3_A")
			(pintype "passive")
		)
		(pad "H12" smd circle
			(at 3.2 -2.1 90)
			(size 0.41 0.41)
			(layers "F.Cu" "F.Mask" "F.Paste")
			(net 14 "GND")
			(pinfunction "VSS")
			(pintype "passive")
		)
		(pad "H13" smd circle
			(at 4 -2.1 90)
			(size 0.41 0.41)
			(layers "F.Cu" "F.Mask" "F.Paste")
			(net 56 "/LPDDR5/LPDDR5_A.CA5")
			(pinfunction "CA5_A")
			(pintype "passive")
		)
		(pad "H14" smd circle
			(at 4.8 -2.1 90)
			(size 0.41 0.41)
			(layers "F.Cu" "F.Mask" "F.Paste")
			(net 12 "+0V9")
			(pinfunction "VDD2L")
			(pintype "passive")
		)
		(pad "H15" smd circle
			(at 5.6 -2.1 90)
			(size 0.41 0.41)
			(layers "F.Cu" "F.Mask" "F.Paste")
			(net 92 "Net-(R69-Pad2)")
			(pinfunction "ZQ_A")
			(pintype "passive")
		)
		(pad "J1" smd circle
			(at -5.6 -1.4 90)
			(size 0.41 0.41)
			(layers "F.Cu" "F.Mask" "F.Paste")
			(net 14 "GND")
			(pinfunction "VSS")
			(pintype "passive")
		)
		(pad "J2" smd circle
			(at -4.8 -1.4 90)
			(size 0.41 0.41)
			(layers "F.Cu" "F.Mask" "F.Paste")
			(net 12 "+0V9")
			(pinfunction "VDD2L")
			(pintype "passive")
		)
		(pad "J3" smd circle
			(at -4 -1.4 90)
			(size 0.41 0.41)
			(layers "F.Cu" "F.Mask" "F.Paste")
			(net 14 "GND")
			(pinfunction "VSS")
			(pintype "passive")
		)
		(pad "J4" smd circle
			(at -3.2 -1.4 90)
			(size 0.41 0.41)
			(layers "F.Cu" "F.Mask" "F.Paste")
			(net 29 "unconnected-(U1-PadJ4)")
			(pinfunction "RFU")
			(pintype "no_connect")
		)
		(pad "J5" smd circle
			(at -2.4 -1.4 90)
			(size 0.41 0.41)
			(layers "F.Cu" "F.Mask" "F.Paste")
			(net 13 "+1V05")
			(pinfunction "VDD2H")
			(pintype "passive")
		)
		(pad "J6" smd circle
			(at -1.6 -1.4 90)
			(size 0.41 0.41)
			(layers "F.Cu" "F.Mask" "F.Paste")
			(net 30 "unconnected-(U1-PadJ6)")
			(pinfunction "RFU")
			(pintype "no_connect")
		)
		(pad "J7" smd circle
			(at -0.8 -1.4 90)
			(size 0.41 0.41)
			(layers "F.Cu" "F.Mask" "F.Paste")
			(net 14 "GND")
			(pinfunction "VSS")
			(pintype "passive")
		)
		(pad "J8" smd circle
			(at 0 -1.4 90)
			(size 0.41 0.41)
			(layers "F.Cu" "F.Mask" "F.Paste")
			(net 14 "GND")
			(pinfunction "VSS")
			(pintype "passive")
		)
		(pad "J9" smd circle
			(at 0.8 -1.4 90)
			(size 0.41 0.41)
			(layers "F.Cu" "F.Mask" "F.Paste")
			(net 50 "/LPDDR5/LPDDR5_A.CK_N")
			(pinfunction "CK_c_A")
			(pintype "passive")
		)
		(pad "J10" smd circle
			(at 1.6 -1.4 90)
			(size 0.41 0.41)
			(layers "F.Cu" "F.Mask" "F.Paste")
			(net 14 "GND")
			(pinfunction "VSS")
			(pintype "passive")
		)
		(pad "J11" smd circle
			(at 2.4 -1.4 90)
			(size 0.41 0.41)
			(layers "F.Cu" "F.Mask" "F.Paste")
			(net 13 "+1V05")
			(pinfunction "VDD2H")
			(pintype "passive")
		)
		(pad "J12" smd circle
			(at 3.2 -1.4 90)
			(size 0.41 0.41)
			(layers "F.Cu" "F.Mask" "F.Paste")
			(net 14 "GND")
			(pinfunction "VSS")
			(pintype "passive")
		)
		(pad "J13" smd circle
			(at 4 -1.4 90)
			(size 0.41 0.41)
			(layers "F.Cu" "F.Mask" "F.Paste")
			(net 14 "GND")
			(pinfunction "VSS")
			(pintype "passive")
		)
		(pad "J14" smd circle
			(at 4.8 -1.4 90)
			(size 0.41 0.41)
			(layers "F.Cu" "F.Mask" "F.Paste")
			(net 12 "+0V9")
			(pinfunction "VDD2L")
			(pintype "passive")
		)
		(pad "J15" smd circle
			(at 5.6 -1.4 90)
			(size 0.41 0.41)
			(layers "F.Cu" "F.Mask" "F.Paste")
			(net 14 "GND")
			(pinfunction "VSS")
			(pintype "passive")
		)
		(pad "K1" smd circle
			(at -5.6 -0.7 90)
			(size 0.41 0.41)
			(layers "F.Cu" "F.Mask" "F.Paste")
			(net 13 "+1V05")
			(pinfunction "VDD2H")
			(pintype "passive")
		)
		(pad "K2" smd circle
			(at -4.8 -0.7 90)
			(size 0.41 0.41)
			(layers "F.Cu" "F.Mask" "F.Paste")
			(net 13 "+1V05")
			(pinfunction "VDD2H")
			(pintype "passive")
		)
		(pad "K3" smd circle
			(at -4 -0.7 90)
			(size 0.41 0.41)
			(layers "F.Cu" "F.Mask" "F.Paste")
			(net 13 "+1V05")
			(pinfunction "VDD2H")
			(pintype "passive")
		)
		(pad "K4" smd circle
			(at -3.2 -0.7 90)
			(size 0.41 0.41)
			(layers "F.Cu" "F.Mask" "F.Paste")
			(net 13 "+1V05")
			(pinfunction "VDD2H")
			(pintype "passive")
		)
		(pad "K5" smd circle
			(at -2.4 -0.7 90)
			(size 0.41 0.41)
			(layers "F.Cu" "F.Mask" "F.Paste")
			(net 13 "+1V05")
			(pinfunction "VDD2H")
			(pintype "passive")
		)
		(pad "K6" smd circle
			(at -1.6 -0.7 90)
			(size 0.41 0.41)
			(layers "F.Cu" "F.Mask" "F.Paste")
			(net 13 "+1V05")
			(pinfunction "VDD2H")
			(pintype "passive")
		)
		(pad "K7" smd circle
			(at -0.8 -0.7 90)
			(size 0.41 0.41)
			(layers "F.Cu" "F.Mask" "F.Paste")
			(net 14 "GND")
			(pinfunction "VSS")
			(pintype "passive")
		)
		(pad "K8" smd circle
			(at 0 -0.7 90)
			(size 0.41 0.41)
			(layers "F.Cu" "F.Mask" "F.Paste")
			(net 14 "GND")
			(pinfunction "VSS")
			(pintype "passive")
		)
		(pad "K9" smd circle
			(at 0.8 -0.7 90)
			(size 0.41 0.41)
			(layers "F.Cu" "F.Mask" "F.Paste")
			(net 14 "GND")
			(pinfunction "VSS")
			(pintype "passive")
		)
		(pad "K10" smd circle
			(at 1.6 -0.7 90)
			(size 0.41 0.41)
			(layers "F.Cu" "F.Mask" "F.Paste")
			(net 13 "+1V05")
			(pinfunction "VDD2H")
			(pintype "passive")
		)
		(pad "K11" smd circle
			(at 2.4 -0.7 90)
			(size 0.41 0.41)
			(layers "F.Cu" "F.Mask" "F.Paste")
			(net 13 "+1V05")
			(pinfunction "VDD2H")
			(pintype "passive")
		)
		(pad "K12" smd circle
			(at 3.2 -0.7 90)
			(size 0.41 0.41)
			(layers "F.Cu" "F.Mask" "F.Paste")
			(net 13 "+1V05")
			(pinfunction "VDD2H")
			(pintype "passive")
		)
		(pad "K13" smd circle
			(at 4 -0.7 90)
			(size 0.41 0.41)
			(layers "F.Cu" "F.Mask" "F.Paste")
			(net 13 "+1V05")
			(pinfunction "VDD2H")
			(pintype "passive")
		)
		(pad "K14" smd circle
			(at 4.8 -0.7 90)
			(size 0.41 0.41)
			(layers "F.Cu" "F.Mask" "F.Paste")
			(net 13 "+1V05")
			(pinfunction "VDD2H")
			(pintype "passive")
		)
		(pad "K15" smd circle
			(at 5.6 -0.7 90)
			(size 0.41 0.41)
			(layers "F.Cu" "F.Mask" "F.Paste")
			(net 13 "+1V05")
			(pinfunction "VDD2H")
			(pintype "passive")
		)
		(pad "L1" smd circle
			(at -5.6 0 90)
			(size 0.41 0.41)
			(layers "F.Cu" "F.Mask" "F.Paste")
			(net 14 "GND")
			(pinfunction "VSS")
			(pintype "passive")
		)
		(pad "L2" smd circle
			(at -4.8 0 90)
			(size 0.41 0.41)
			(layers "F.Cu" "F.Mask" "F.Paste")
			(net 14 "GND")
			(pinfunction "VSS")
			(pintype "passive")
		)
		(pad "L3" smd circle
			(at -4 0 90)
			(size 0.41 0.41)
			(layers "F.Cu" "F.Mask" "F.Paste")
			(net 14 "GND")
			(pinfunction "VSS")
			(pintype "passive")
		)
		(pad "L4" smd circle
			(at -3.2 0 90)
			(size 0.41 0.41)
			(layers "F.Cu" "F.Mask" "F.Paste")
			(net 14 "GND")
			(pinfunction "VSS")
			(pintype "passive")
		)
		(pad "L5" smd circle
			(at -2.4 0 90)
			(size 0.41 0.41)
			(layers "F.Cu" "F.Mask" "F.Paste")
			(net 14 "GND")
			(pinfunction "VSS")
			(pintype "passive")
		)
		(pad "L6" smd circle
			(at -1.6 0 90)
			(size 0.41 0.41)
			(layers "F.Cu" "F.Mask" "F.Paste")
			(net 13 "+1V05")
			(pinfunction "VDD2H")
			(pintype "passive")
		)
		(pad "L7" smd circle
			(at -0.8 0 90)
			(size 0.41 0.41)
			(layers "F.Cu" "F.Mask" "F.Paste")
			(net 13 "+1V05")
			(pinfunction "VDD2H")
			(pintype "passive")
		)
		(pad "L8" smd circle
			(at 0 0 90)
			(size 0.41 0.41)
			(layers "F.Cu" "F.Mask" "F.Paste")
			(net 13 "+1V05")
			(pinfunction "VDD2H")
			(pintype "passive")
		)
		(pad "L9" smd circle
			(at 0.8 0 90)
			(size 0.41 0.41)
			(layers "F.Cu" "F.Mask" "F.Paste")
			(net 13 "+1V05")
			(pinfunction "VDD2H")
			(pintype "passive")
		)
		(pad "L10" smd circle
			(at 1.6 0 90)
			(size 0.41 0.41)
			(layers "F.Cu" "F.Mask" "F.Paste")
			(net 13 "+1V05")
			(pinfunction "VDD2H")
			(pintype "passive")
		)
		(pad "L11" smd circle
			(at 2.4 0 90)
			(size 0.41 0.41)
			(layers "F.Cu" "F.Mask" "F.Paste")
			(net 14 "GND")
			(pinfunction "VSS")
			(pintype "passive")
		)
		(pad "L12" smd circle
			(at 3.2 0 90)
			(size 0.41 0.41)
			(layers "F.Cu" "F.Mask" "F.Paste")
			(net 14 "GND")
			(pinfunction "VSS")
			(pintype "passive")
		)
		(pad "L13" smd circle
			(at 4 0 90)
			(size 0.41 0.41)
			(layers "F.Cu" "F.Mask" "F.Paste")
			(net 14 "GND")
			(pinfunction "VSS")
			(pintype "passive")
		)
		(pad "L14" smd circle
			(at 4.8 0 90)
			(size 0.41 0.41)
			(layers "F.Cu" "F.Mask" "F.Paste")
			(net 14 "GND")
			(pinfunction "VSS")
			(pintype "passive")
		)
		(pad "L15" smd circle
			(at 5.6 0 90)
			(size 0.41 0.41)
			(layers "F.Cu" "F.Mask" "F.Paste")
			(net 14 "GND")
			(pinfunction "VSS")
			(pintype "passive")
		)
		(pad "M1" smd circle
			(at -5.6 0.7 90)
			(size 0.41 0.41)
			(layers "F.Cu" "F.Mask" "F.Paste")
			(net 13 "+1V05")
			(pinfunction "VDD2H")
			(pintype "passive")
		)
		(pad "M2" smd circle
			(at -4.8 0.7 90)
			(size 0.41 0.41)
			(layers "F.Cu" "F.Mask" "F.Paste")
			(net 13 "+1V05")
			(pinfunction "VDD2H")
			(pintype "passive")
		)
	)
)
